#ISCELL
  mstr_misc dns *
  *
#ISCELL
  pure_quanta quanta_title_block_c *
  *
#ISCELL
  pure_quanta_power universal_gnd *
  page467_i1
#ISCELL
  pure_quanta_power universal_power *
  page467_i10
#ISCELL
  standard offpage *
  page467_i12
#ISCELL
  standard offpage *
  page467_i13
#CELL
  pure_quanta q_res *
  page467_i2
#ISCELL
  pure_quanta_power universal_gnd *
  page467_i3
#CELL
  pure_quanta q_res *
  page467_i4
#CELL
  pure_quanta q_res *
  page467_i5
#CELL
  pure_quanta q_res *
  page467_i6
